FILE_TYPE=LIBRARY_PARTS;
TIME=' Created/Modified on Tue Sep 11 13:44:28 2001' ;
primitive 'FET_N';
  pin
    'GATE':
      PIN_NUMBER='(1)';
      PINUSE='UNSPEC';
      NO_LOAD_CHECK='BOTH';
      NO_IO_CHECK='BOTH';
      ALLOW_CONNECT='TRUE';
    'SRC':
      PIN_NUMBER='(2)';
      PINUSE='UNSPEC';
      NO_LOAD_CHECK='BOTH';
      NO_IO_CHECK='BOTH';
      ALLOW_CONNECT='TRUE';
    'DRN':
      PIN_NUMBER='(3)';
      PINUSE='UNSPEC';
      NO_LOAD_CHECK='BOTH';
      NO_IO_CHECK='BOTH';
      ALLOW_CONNECT='TRUE';
  end_pin;
  body
    PART_NAME='FET_N';
    PHYS_DES_PREFIX='Q';
  end_body;
end_primitive;
primitive 'FET_N_SOT404A','FET_N_SOT404ALF','FET_N_SOT369ALF';
  pin
    'GATE':
      PIN_NUMBER='(1)';
      PINUSE='UNSPEC';
      NO_LOAD_CHECK='BOTH';
      NO_IO_CHECK='BOTH';
      ALLOW_CONNECT='TRUE';
    'SRC':
      PIN_NUMBER='(3)';
      PINUSE='UNSPEC';
      NO_LOAD_CHECK='BOTH';
      NO_IO_CHECK='BOTH';
      ALLOW_CONNECT='TRUE';
    'DRN':
      PIN_NUMBER='(4)';
      PINUSE='UNSPEC';
      NO_LOAD_CHECK='BOTH';
      NO_IO_CHECK='BOTH';
      ALLOW_CONNECT='TRUE';
  end_pin;
  body
    PART_NAME='FET_N';
    PHYS_DES_PREFIX='Q';
  end_body;
end_primitive;
primitive 'FET_N_TH','FET_N_THLF';
  pin
    'GATE':
      PIN_NUMBER='(1)';
      PINUSE='UNSPEC';
      NO_LOAD_CHECK='BOTH';
      NO_IO_CHECK='BOTH';
      ALLOW_CONNECT='TRUE';
    'SRC':
      PIN_NUMBER='(3)';
      PINUSE='UNSPEC';
      NO_LOAD_CHECK='BOTH';
      NO_IO_CHECK='BOTH';
      ALLOW_CONNECT='TRUE';
    'DRN':
      PIN_NUMBER='(2)';
      PINUSE='UNSPEC';
      NO_LOAD_CHECK='BOTH';
      NO_IO_CHECK='BOTH';
      ALLOW_CONNECT='TRUE';
  end_pin;
  body
    PART_NAME='FET_N';
    PHYS_DES_PREFIX='Q';
  end_body;
end_primitive;
primitive 'FET_N_SOT428A';
  pin
    'GATE':
      PIN_NUMBER='(1)';
      PINUSE='UNSPEC';
      NO_LOAD_CHECK='BOTH';
      NO_IO_CHECK='BOTH';
      ALLOW_CONNECT='TRUE';
    'SRC':
      PIN_NUMBER='(2)';
      PINUSE='UNSPEC';
      NO_LOAD_CHECK='BOTH';
      NO_IO_CHECK='BOTH';
      ALLOW_CONNECT='TRUE';
    'DRN':
      PIN_NUMBER='(3)';
      PINUSE='UNSPEC';
      NO_LOAD_CHECK='BOTH';
      NO_IO_CHECK='BOTH';
      ALLOW_CONNECT='TRUE';
  end_pin;
  body
    PART_NAME='FET_N';
    PHYS_DES_PREFIX='Q';
  end_body;
end_primitive;
primitive 'FET_N_SOT23DSGLF';
  pin
    'GATE':
      PIN_NUMBER='(3)';
      PINUSE='UNSPEC';
      NO_LOAD_CHECK='BOTH';
      NO_IO_CHECK='BOTH';
      ALLOW_CONNECT='TRUE';
    'SRC':
      PIN_NUMBER='(2)';
      PINUSE='UNSPEC';
      NO_LOAD_CHECK='BOTH';
      NO_IO_CHECK='BOTH';
      ALLOW_CONNECT='TRUE';
    'DRN':
      PIN_NUMBER='(1)';
      PINUSE='UNSPEC';
      NO_LOAD_CHECK='BOTH';
      NO_IO_CHECK='BOTH';
      ALLOW_CONNECT='TRUE';
  end_pin;
  body
    PART_NAME='FET_N';
    PHYS_DES_PREFIX='Q';
  end_body;
end_primitive;
END.
